(kicad_pcb
	(version 20260206)
	(generator "pcbnew")
	(generator_version "10.0")
	(general
		(thickness 1.6)
		(legacy_teardrops no)
	)
	(paper "A4")
	(title_block
		(title "04192023_DAF0TMB3IC0_F0TG_MB_C_brd_V02_OCP.brd")
		(comment 1 "Grand Teton / footprints 2890-2895 of 8354")
	)
	(layers
		(0 "F.Cu" signal "TOP")
		(4 "In1.Cu" signal "GND")
		(6 "In2.Cu" signal "IN1")
		(8 "In3.Cu" signal "GND1")
		(10 "In4.Cu" signal "IN2")
		(12 "In5.Cu" signal "GND2")
		(14 "In6.Cu" signal "IN3")
		(16 "In7.Cu" signal "GND3")
		(18 "In8.Cu" signal "VCC")
		(20 "In9.Cu" signal "VCC1")
		(22 "In10.Cu" signal "GND4")
		(24 "In11.Cu" signal "IN4")
		(26 "In12.Cu" signal "GND5")
		(28 "In13.Cu" signal "IN5")
		(30 "In14.Cu" signal "GND6")
		(32 "In15.Cu" signal "IN6")
		(34 "In16.Cu" signal "GND7")
		(2 "B.Cu" signal "BOTTOM")
		(9 "F.Adhes" user "F.Adhesive")
		(11 "B.Adhes" user "B.Adhesive")
		(13 "F.Paste" user "Package Geometry/Pastemask Top")
		(15 "B.Paste" user "Package Geometry/Pastemask Bottom")
		(5 "F.SilkS" user "Ref Des/Silkscreen Top")
		(7 "B.SilkS" user "Ref Des/Silkscreen Bottom")
		(1 "F.Mask" user "Board Geometry/Soldermask Top")
		(3 "B.Mask" user "Board Geometry/Soldermask Bottom")
		(17 "Dwgs.User" user "User.Drawings")
		(19 "Cmts.User" user "User.Comments")
		(21 "Eco1.User" user "User.Eco1")
		(23 "Eco2.User" user "User.Eco2")
		(25 "Edge.Cuts" user "Board Geometry/Outline")
		(27 "Margin" user)
		(31 "F.CrtYd" user "Package Geometry/Place Bound Top")
		(29 "B.CrtYd" user "Package Geometry/Place Bound Bottom")
		(35 "F.Fab" user "Ref Des/Assembly Top")
		(33 "B.Fab" user "Ref Des/Assembly Bottom")
	)
	(footprint ""
		(layer "F.Cu")
		(at 105.960164 -255.555242)
		(property "Reference" "C2671"
			(at 0 0 0)
			(layer "F.SilkS")
			(hide yes)
			(effects
				(font
					(size 1.27 1.27)
				)
			)
		)
		(property "Value" ""
			(at 0 0 0)
			(layer "F.Fab")
			(effects
				(font
					(size 1.27 1.27)
				)
			)
		)
		(duplicate_pad_numbers_are_jumpers no)
		(fp_line
			(start -0.7874 -0.4064)
			(end 0.7874 -0.4064)
			(stroke
				(width 0.1524)
				(type default)
			)
			(layer "F.SilkS")
		)
		(fp_line
			(start -0.7874 0.4064)
			(end -0.7874 -0.4064)
			(stroke
				(width 0.1524)
				(type default)
			)
			(layer "F.SilkS")
		)
		(fp_line
			(start 0.7874 -0.4064)
			(end 0.7874 0.4064)
			(stroke
				(width 0.1524)
				(type default)
			)
			(layer "F.SilkS")
		)
		(fp_line
			(start 0.7874 0.4064)
			(end -0.7874 0.4064)
			(stroke
				(width 0.1524)
				(type default)
			)
			(layer "F.SilkS")
		)
		(fp_line
			(start -0.67945 -0.305054)
			(end -0.12065 -0.305054)
			(stroke
				(width 0.1)
				(type default)
			)
			(layer "F.Fab")
		)
		(fp_line
			(start -0.67945 0.3048)
			(end -0.67945 -0.305054)
			(stroke
				(width 0.1)
				(type default)
			)
			(layer "F.Fab")
		)
		(fp_line
			(start -0.12065 -0.305054)
			(end -0.12065 -0.2794)
			(stroke
				(width 0.1)
				(type default)
			)
			(layer "F.Fab")
		)
		(fp_line
			(start -0.12065 -0.2794)
			(end 0.12065 -0.2794)
			(stroke
				(width 0.1)
				(type default)
			)
			(layer "F.Fab")
		)
		(fp_line
			(start -0.12065 0.2794)
			(end -0.12065 0.3048)
			(stroke
				(width 0.1)
				(type default)
			)
			(layer "F.Fab")
		)
		(fp_line
			(start -0.12065 0.3048)
			(end -0.67945 0.3048)
			(stroke
				(width 0.1)
				(type default)
			)
			(layer "F.Fab")
		)
		(fp_line
			(start 0.120396 0.2794)
			(end -0.12065 0.2794)
			(stroke
				(width 0.1)
				(type default)
			)
			(layer "F.Fab")
		)
		(fp_line
			(start 0.120396 0.3048)
			(end 0.120396 0.2794)
			(stroke
				(width 0.1)
				(type default)
			)
			(layer "F.Fab")
		)
		(fp_line
			(start 0.12065 -0.3048)
			(end 0.67945 -0.3048)
			(stroke
				(width 0.1)
				(type default)
			)
			(layer "F.Fab")
		)
		(fp_line
			(start 0.12065 -0.2794)
			(end 0.12065 -0.3048)
			(stroke
				(width 0.1)
				(type default)
			)
			(layer "F.Fab")
		)
		(fp_line
			(start 0.67945 -0.3048)
			(end 0.67945 0.3048)
			(stroke
				(width 0.1)
				(type default)
			)
			(layer "F.Fab")
		)
		(fp_line
			(start 0.67945 0.3048)
			(end 0.120396 0.3048)
			(stroke
				(width 0.1)
				(type default)
			)
			(layer "F.Fab")
		)
		(pad "1" smd circle
			(at -0.40005 0)
			(size 0 0)
			(layers "F.Cu" "F.Mask" "F.Paste")
			(net "PVDD18_S5_P1")
		)
		(pad "2" smd circle
			(at 0.40005 0)
			(size 0 0)
			(layers "F.Cu" "F.Mask" "F.Paste")
			(net "GND")
		)
	)
	(footprint ""
		(layer "F.Cu")
		(at 307.741574 -24.090884)
		(property "Reference" "C22"
			(at 0 0 0)
			(layer "F.SilkS")
			(hide yes)
			(effects
				(font
					(size 1.27 1.27)
				)
			)
		)
		(property "Value" ""
			(at 0 0 0)
			(layer "F.Fab")
			(effects
				(font
					(size 1.27 1.27)
				)
			)
		)
		(duplicate_pad_numbers_are_jumpers no)
		(fp_line
			(start -0.7874 -0.4064)
			(end 0.7874 -0.4064)
			(stroke
				(width 0.1524)
				(type default)
			)
			(layer "F.SilkS")
		)
		(fp_line
			(start -0.7874 0.4064)
			(end -0.7874 -0.4064)
			(stroke
				(width 0.1524)
				(type default)
			)
			(layer "F.SilkS")
		)
		(fp_line
			(start 0.7874 -0.4064)
			(end 0.7874 0.4064)
			(stroke
				(width 0.1524)
				(type default)
			)
			(layer "F.SilkS")
		)
		(fp_line
			(start 0.7874 0.4064)
			(end -0.7874 0.4064)
			(stroke
				(width 0.1524)
				(type default)
			)
			(layer "F.SilkS")
		)
		(fp_line
			(start -0.67945 -0.305054)
			(end -0.12065 -0.305054)
			(stroke
				(width 0.1)
				(type default)
			)
			(layer "F.Fab")
		)
		(fp_line
			(start -0.67945 0.3048)
			(end -0.67945 -0.305054)
			(stroke
				(width 0.1)
				(type default)
			)
			(layer "F.Fab")
		)
		(fp_line
			(start -0.12065 -0.305054)
			(end -0.12065 -0.2794)
			(stroke
				(width 0.1)
				(type default)
			)
			(layer "F.Fab")
		)
		(fp_line
			(start -0.12065 -0.2794)
			(end 0.12065 -0.2794)
			(stroke
				(width 0.1)
				(type default)
			)
			(layer "F.Fab")
		)
		(fp_line
			(start -0.12065 0.2794)
			(end -0.12065 0.3048)
			(stroke
				(width 0.1)
				(type default)
			)
			(layer "F.Fab")
		)
		(fp_line
			(start -0.12065 0.3048)
			(end -0.67945 0.3048)
			(stroke
				(width 0.1)
				(type default)
			)
			(layer "F.Fab")
		)
		(fp_line
			(start 0.120396 0.2794)
			(end -0.12065 0.2794)
			(stroke
				(width 0.1)
				(type default)
			)
			(layer "F.Fab")
		)
		(fp_line
			(start 0.120396 0.3048)
			(end 0.120396 0.2794)
			(stroke
				(width 0.1)
				(type default)
			)
			(layer "F.Fab")
		)
		(fp_line
			(start 0.12065 -0.3048)
			(end 0.67945 -0.3048)
			(stroke
				(width 0.1)
				(type default)
			)
			(layer "F.Fab")
		)
		(fp_line
			(start 0.12065 -0.2794)
			(end 0.12065 -0.3048)
			(stroke
				(width 0.1)
				(type default)
			)
			(layer "F.Fab")
		)
		(fp_line
			(start 0.67945 -0.3048)
			(end 0.67945 0.3048)
			(stroke
				(width 0.1)
				(type default)
			)
			(layer "F.Fab")
		)
		(fp_line
			(start 0.67945 0.3048)
			(end 0.120396 0.3048)
			(stroke
				(width 0.1)
				(type default)
			)
			(layer "F.Fab")
		)
		(pad "1" smd circle
			(at -0.40005 0)
			(size 0 0)
			(layers "F.Cu" "F.Mask" "F.Paste")
			(net "U9_NR")
		)
		(pad "2" smd circle
			(at 0.40005 0)
			(size 0 0)
			(layers "F.Cu" "F.Mask" "F.Paste")
			(net "GND")
		)
	)
	(footprint ""
		(layer "F.Cu")
		(at 66.666364 -151.549862 -90)
		(property "Reference" "PC22"
			(at 0 0 270)
			(layer "F.SilkS")
			(hide yes)
			(effects
				(font
					(size 1.27 1.27)
				)
			)
		)
		(property "Value" ""
			(at 0 0 270)
			(layer "F.Fab")
			(effects
				(font
					(size 1.27 1.27)
				)
			)
		)
		(duplicate_pad_numbers_are_jumpers no)
		(fp_line
			(start -0.7874 0.4064)
			(end -0.7874 -0.4064)
			(stroke
				(width 0.1524)
				(type default)
			)
			(layer "F.SilkS")
		)
		(fp_line
			(start 0.7874 0.4064)
			(end -0.7874 0.4064)
			(stroke
				(width 0.1524)
				(type default)
			)
			(layer "F.SilkS")
		)
		(fp_line
			(start -0.7874 -0.4064)
			(end 0.7874 -0.4064)
			(stroke
				(width 0.1524)
				(type default)
			)
			(layer "F.SilkS")
		)
		(fp_line
			(start 0.7874 -0.4064)
			(end 0.7874 0.4064)
			(stroke
				(width 0.1524)
				(type default)
			)
			(layer "F.SilkS")
		)
		(fp_line
			(start -0.67945 0.3048)
			(end -0.67945 -0.305054)
			(stroke
				(width 0.1)
				(type default)
			)
			(layer "F.Fab")
		)
		(fp_line
			(start -0.12065 0.3048)
			(end -0.67945 0.3048)
			(stroke
				(width 0.1)
				(type default)
			)
			(layer "F.Fab")
		)
		(fp_line
			(start 0.120396 0.3048)
			(end 0.120396 0.2794)
			(stroke
				(width 0.1)
				(type default)
			)
			(layer "F.Fab")
		)
		(fp_line
			(start 0.67945 0.3048)
			(end 0.120396 0.3048)
			(stroke
				(width 0.1)
				(type default)
			)
			(layer "F.Fab")
		)
		(fp_line
			(start -0.12065 0.2794)
			(end -0.12065 0.3048)
			(stroke
				(width 0.1)
				(type default)
			)
			(layer "F.Fab")
		)
		(fp_line
			(start 0.120396 0.2794)
			(end -0.12065 0.2794)
			(stroke
				(width 0.1)
				(type default)
			)
			(layer "F.Fab")
		)
		(fp_line
			(start -0.12065 -0.2794)
			(end 0.12065 -0.2794)
			(stroke
				(width 0.1)
				(type default)
			)
			(layer "F.Fab")
		)
		(fp_line
			(start 0.12065 -0.2794)
			(end 0.12065 -0.3048)
			(stroke
				(width 0.1)
				(type default)
			)
			(layer "F.Fab")
		)
		(fp_line
			(start 0.12065 -0.3048)
			(end 0.67945 -0.3048)
			(stroke
				(width 0.1)
				(type default)
			)
			(layer "F.Fab")
		)
		(fp_line
			(start 0.67945 -0.3048)
			(end 0.67945 0.3048)
			(stroke
				(width 0.1)
				(type default)
			)
			(layer "F.Fab")
		)
		(fp_line
			(start -0.67945 -0.305054)
			(end -0.12065 -0.305054)
			(stroke
				(width 0.1)
				(type default)
			)
			(layer "F.Fab")
		)
		(fp_line
			(start -0.12065 -0.305054)
			(end -0.12065 -0.2794)
			(stroke
				(width 0.1)
				(type default)
			)
			(layer "F.Fab")
		)
		(pad "1" smd circle
			(at -0.40005 0 270)
			(size 0 0)
			(layers "F.Cu" "F.Mask" "F.Paste")
			(net "SW_P12V_AUX_PVDD18_S5_P1_FLT")
		)
		(pad "2" smd circle
			(at 0.40005 0 270)
			(size 0 0)
			(layers "F.Cu" "F.Mask" "F.Paste")
			(net "GND")
		)
	)
	(footprint ""
		(layer "F.Cu")
		(at 2.677922 -58.875168 -90)
		(property "Reference" "R930"
			(at 0 0 270)
			(layer "F.SilkS")
			(hide yes)
			(effects
				(font
					(size 1.27 1.27)
				)
			)
		)
		(property "Value" ""
			(at 0 0 270)
			(layer "F.Fab")
			(effects
				(font
					(size 1.27 1.27)
				)
			)
		)
		(duplicate_pad_numbers_are_jumpers no)
		(fp_line
			(start -0.7874 0.4064)
			(end -0.7874 -0.4064)
			(stroke
				(width 0.1524)
				(type default)
			)
			(layer "F.SilkS")
		)
		(fp_line
			(start 0.7874 0.4064)
			(end -0.7874 0.4064)
			(stroke
				(width 0.1524)
				(type default)
			)
			(layer "F.SilkS")
		)
		(fp_line
			(start -0.7874 -0.4064)
			(end 0.7874 -0.4064)
			(stroke
				(width 0.1524)
				(type default)
			)
			(layer "F.SilkS")
		)
		(fp_line
			(start 0.7874 -0.4064)
			(end 0.7874 0.4064)
			(stroke
				(width 0.1524)
				(type default)
			)
			(layer "F.SilkS")
		)
		(fp_line
			(start -0.67945 0.3048)
			(end -0.67945 -0.305054)
			(stroke
				(width 0.1)
				(type default)
			)
			(layer "F.Fab")
		)
		(fp_line
			(start -0.12065 0.3048)
			(end -0.67945 0.3048)
			(stroke
				(width 0.1)
				(type default)
			)
			(layer "F.Fab")
		)
		(fp_line
			(start 0.120396 0.3048)
			(end 0.120396 0.2794)
			(stroke
				(width 0.1)
				(type default)
			)
			(layer "F.Fab")
		)
		(fp_line
			(start 0.67945 0.3048)
			(end 0.120396 0.3048)
			(stroke
				(width 0.1)
				(type default)
			)
			(layer "F.Fab")
		)
		(fp_line
			(start -0.12065 0.2794)
			(end -0.12065 0.3048)
			(stroke
				(width 0.1)
				(type default)
			)
			(layer "F.Fab")
		)
		(fp_line
			(start 0.120396 0.2794)
			(end -0.12065 0.2794)
			(stroke
				(width 0.1)
				(type default)
			)
			(layer "F.Fab")
		)
		(fp_line
			(start -0.12065 -0.2794)
			(end 0.12065 -0.2794)
			(stroke
				(width 0.1)
				(type default)
			)
			(layer "F.Fab")
		)
		(fp_line
			(start 0.12065 -0.2794)
			(end 0.12065 -0.3048)
			(stroke
				(width 0.1)
				(type default)
			)
			(layer "F.Fab")
		)
		(fp_line
			(start 0.12065 -0.3048)
			(end 0.67945 -0.3048)
			(stroke
				(width 0.1)
				(type default)
			)
			(layer "F.Fab")
		)
		(fp_line
			(start 0.67945 -0.3048)
			(end 0.67945 0.3048)
			(stroke
				(width 0.1)
				(type default)
			)
			(layer "F.Fab")
		)
		(fp_line
			(start -0.67945 -0.305054)
			(end -0.12065 -0.305054)
			(stroke
				(width 0.1)
				(type default)
			)
			(layer "F.Fab")
		)
		(fp_line
			(start -0.12065 -0.305054)
			(end -0.12065 -0.2794)
			(stroke
				(width 0.1)
				(type default)
			)
			(layer "F.Fab")
		)
		(pad "1" smd circle
			(at -0.40005 0 270)
			(size 0 0)
			(layers "F.Cu" "F.Mask" "F.Paste")
			(net "CPU1_XTRIG_L5")
		)
		(pad "2" smd circle
			(at 0.40005 0 270)
			(size 0 0)
			(layers "F.Cu" "F.Mask" "F.Paste")
			(net "CPU1_XTRIG_R1_L5")
		)
	)
	(footprint ""
		(layer "F.Cu")
		(at 208.894426 -115.657376)
		(property "Reference" "R195"
			(at 0 0 0)
			(layer "F.SilkS")
			(hide yes)
			(effects
				(font
					(size 1.27 1.27)
				)
			)
		)
		(property "Value" ""
			(at 0 0 0)
			(layer "F.Fab")
			(effects
				(font
					(size 1.27 1.27)
				)
			)
		)
		(duplicate_pad_numbers_are_jumpers no)
		(fp_line
			(start -0.7874 -0.4064)
			(end 0.7874 -0.4064)
			(stroke
				(width 0.1524)
				(type default)
			)
			(layer "F.SilkS")
		)
		(fp_line
			(start -0.7874 0.4064)
			(end -0.7874 -0.4064)
			(stroke
				(width 0.1524)
				(type default)
			)
			(layer "F.SilkS")
		)
		(fp_line
			(start 0.7874 -0.4064)
			(end 0.7874 0.4064)
			(stroke
				(width 0.1524)
				(type default)
			)
			(layer "F.SilkS")
		)
		(fp_line
			(start 0.7874 0.4064)
			(end -0.7874 0.4064)
			(stroke
				(width 0.1524)
				(type default)
			)
			(layer "F.SilkS")
		)
		(fp_line
			(start -0.67945 -0.305054)
			(end -0.12065 -0.305054)
			(stroke
				(width 0.1)
				(type default)
			)
			(layer "F.Fab")
		)
		(fp_line
			(start -0.67945 0.3048)
			(end -0.67945 -0.305054)
			(stroke
				(width 0.1)
				(type default)
			)
			(layer "F.Fab")
		)
		(fp_line
			(start -0.12065 -0.305054)
			(end -0.12065 -0.2794)
			(stroke
				(width 0.1)
				(type default)
			)
			(layer "F.Fab")
		)
		(fp_line
			(start -0.12065 -0.2794)
			(end 0.12065 -0.2794)
			(stroke
				(width 0.1)
				(type default)
			)
			(layer "F.Fab")
		)
		(fp_line
			(start -0.12065 0.2794)
			(end -0.12065 0.3048)
			(stroke
				(width 0.1)
				(type default)
			)
			(layer "F.Fab")
		)
		(fp_line
			(start -0.12065 0.3048)
			(end -0.67945 0.3048)
			(stroke
				(width 0.1)
				(type default)
			)
			(layer "F.Fab")
		)
		(fp_line
			(start 0.120396 0.2794)
			(end -0.12065 0.2794)
			(stroke
				(width 0.1)
				(type default)
			)
			(layer "F.Fab")
		)
		(fp_line
			(start 0.120396 0.3048)
			(end 0.120396 0.2794)
			(stroke
				(width 0.1)
				(type default)
			)
			(layer "F.Fab")
		)
		(fp_line
			(start 0.12065 -0.3048)
			(end 0.67945 -0.3048)
			(stroke
				(width 0.1)
				(type default)
			)
			(layer "F.Fab")
		)
		(fp_line
			(start 0.12065 -0.2794)
			(end 0.12065 -0.3048)
			(stroke
				(width 0.1)
				(type default)
			)
			(layer "F.Fab")
		)
		(fp_line
			(start 0.67945 -0.3048)
			(end 0.67945 0.3048)
			(stroke
				(width 0.1)
				(type default)
			)
			(layer "F.Fab")
		)
		(fp_line
			(start 0.67945 0.3048)
			(end 0.120396 0.3048)
			(stroke
				(width 0.1)
				(type default)
			)
			(layer "F.Fab")
		)
		(pad "1" smd circle
			(at -0.40005 0)
			(size 0 0)
			(layers "F.Cu" "F.Mask" "F.Paste")
			(net "FM_CPU1_PWRGD_OUT")
		)
		(pad "2" smd circle
			(at 0.40005 0)
			(size 0 0)
			(layers "F.Cu" "F.Mask" "F.Paste")
			(net "CPU1_PWRGD_OUT")
		)
	)
	(footprint ""
		(layer "F.Cu")
		(at 261.468616 -75.770994 180)
		(property "Reference" "R3773"
			(at 0 0 180)
			(layer "F.SilkS")
			(hide yes)
			(effects
				(font
					(size 1.27 1.27)
				)
			)
		)
		(property "Value" ""
			(at 0 0 180)
			(layer "F.Fab")
			(effects
				(font
					(size 1.27 1.27)
				)
			)
		)
		(duplicate_pad_numbers_are_jumpers no)
		(fp_line
			(start 0.7874 0.4064)
			(end -0.7874 0.4064)
			(stroke
				(width 0.1524)
				(type default)
			)
			(layer "F.SilkS")
		)
		(fp_line
			(start 0.7874 -0.4064)
			(end 0.7874 0.4064)
			(stroke
				(width 0.1524)
				(type default)
			)
			(layer "F.SilkS")
		)
		(fp_line
			(start -0.7874 0.4064)
			(end -0.7874 -0.4064)
			(stroke
				(width 0.1524)
				(type default)
			)
			(layer "F.SilkS")
		)
		(fp_line
			(start -0.7874 -0.4064)
			(end 0.7874 -0.4064)
			(stroke
				(width 0.1524)
				(type default)
			)
			(layer "F.SilkS")
		)
		(fp_line
			(start 0.67945 0.3048)
			(end 0.120396 0.3048)
			(stroke
				(width 0.1)
				(type default)
			)
			(layer "F.Fab")
		)
		(fp_line
			(start 0.67945 -0.3048)
			(end 0.67945 0.3048)
			(stroke
				(width 0.1)
				(type default)
			)
			(layer "F.Fab")
		)
		(fp_line
			(start 0.12065 -0.2794)
			(end 0.12065 -0.3048)
			(stroke
				(width 0.1)
				(type default)
			)
			(layer "F.Fab")
		)
		(fp_line
			(start 0.12065 -0.3048)
			(end 0.67945 -0.3048)
			(stroke
				(width 0.1)
				(type default)
			)
			(layer "F.Fab")
		)
		(fp_line
			(start 0.120396 0.3048)
			(end 0.120396 0.2794)
			(stroke
				(width 0.1)
				(type default)
			)
			(layer "F.Fab")
		)
		(fp_line
			(start 0.120396 0.2794)
			(end -0.12065 0.2794)
			(stroke
				(width 0.1)
				(type default)
			)
			(layer "F.Fab")
		)
		(fp_line
			(start -0.12065 0.3048)
			(end -0.67945 0.3048)
			(stroke
				(width 0.1)
				(type default)
			)
			(layer "F.Fab")
		)
		(fp_line
			(start -0.12065 0.2794)
			(end -0.12065 0.3048)
			(stroke
				(width 0.1)
				(type default)
			)
			(layer "F.Fab")
		)
		(fp_line
			(start -0.12065 -0.2794)
			(end 0.12065 -0.2794)
			(stroke
				(width 0.1)
				(type default)
			)
			(layer "F.Fab")
		)
		(fp_line
			(start -0.12065 -0.305054)
			(end -0.12065 -0.2794)
			(stroke
				(width 0.1)
				(type default)
			)
			(layer "F.Fab")
		)
		(fp_line
			(start -0.67945 0.3048)
			(end -0.67945 -0.305054)
			(stroke
				(width 0.1)
				(type default)
			)
			(layer "F.Fab")
		)
		(fp_line
			(start -0.67945 -0.305054)
			(end -0.12065 -0.305054)
			(stroke
				(width 0.1)
				(type default)
			)
			(layer "F.Fab")
		)
		(pad "1" smd circle
			(at -0.40005 0 180)
			(size 0 0)
			(layers "F.Cu" "F.Mask" "F.Paste")
			(net "P3V3_AUX")
		)
		(pad "2" smd circle
			(at 0.40005 0 180)
			(size 0 0)
			(layers "F.Cu" "F.Mask" "F.Paste")
			(net "RST_SMB_E1S_0_N")
		)
	)
)
